#ISCELL
  pure_quanta quanta_title_block_c *
  *
#ISCELL
  pure_quanta_power p1v0 *
  page387_i20
#CELL
  pure_quanta q_cap *
  page387_i21
#ISCELL
  pure_quanta_power universal_gnd *
  page387_i22
#ISCELL
  pure_quanta_power universal_gnd *
  page387_i23
#CELL
  pure_quanta q_res *
  page387_i24
#ISCELL
  pure_quanta_power universal_gnd *
  page387_i25
#ISCELL
  pure_quanta_power universal_gnd *
  page387_i26
#CELL
  pure_quanta m24m02drmn6tp *
  page387_i3
#ISCELL
  standard offpage *
  page387_i4
#ISCELL
  standard offpage *
  page387_i5
#CELL
  pure_quanta q_res *
  page387_i6
#CELL
  pure_quanta q_res *
  page387_i7
